(kicad_pcb
	(version 20260206)
	(generator "pcbnew")
	(generator_version "10.0")
	(general
		(thickness 1.6)
		(legacy_teardrops no)
	)
	(paper "A4")
	(title_block
		(title "03242023_DA0F0TMBIJ0_F0T_Motherboard_J_brd_V01_OCP.brd")
		(comment 1 "Grand Teton / footprints 5157-5162 of 6105")
	)
	(layers
		(0 "F.Cu" signal "TOP")
		(4 "In1.Cu" signal "GND")
		(6 "In2.Cu" signal "IN1")
		(8 "In3.Cu" signal "GND1")
		(10 "In4.Cu" signal "IN2")
		(12 "In5.Cu" signal "GND2")
		(14 "In6.Cu" signal "IN3")
		(16 "In7.Cu" signal "GND3")
		(18 "In8.Cu" signal "VCC")
		(20 "In9.Cu" signal "VCC1")
		(22 "In10.Cu" signal "GND4")
		(24 "In11.Cu" signal "IN4")
		(26 "In12.Cu" signal "GND5")
		(28 "In13.Cu" signal "IN5")
		(30 "In14.Cu" signal "GND6")
		(32 "In15.Cu" signal "IN6")
		(34 "In16.Cu" signal "GND7")
		(2 "B.Cu" signal "BOTTOM")
		(9 "F.Adhes" user "F.Adhesive")
		(11 "B.Adhes" user "B.Adhesive")
		(13 "F.Paste" user "Package Geometry/Pastemask Top")
		(15 "B.Paste" user "Package Geometry/Pastemask Bottom")
		(5 "F.SilkS" user "Ref Des/Silkscreen Top")
		(7 "B.SilkS" user "Ref Des/Silkscreen Bottom")
		(1 "F.Mask" user "Board Geometry/Soldermask Top")
		(3 "B.Mask" user "Board Geometry/Soldermask Bottom")
		(17 "Dwgs.User" user "User.Drawings")
		(19 "Cmts.User" user "User.Comments")
		(21 "Eco1.User" user "User.Eco1")
		(23 "Eco2.User" user "User.Eco2")
		(25 "Edge.Cuts" user "Board Geometry/Outline")
		(27 "Margin" user)
		(31 "F.CrtYd" user "Package Geometry/Place Bound Top")
		(29 "B.CrtYd" user "Package Geometry/Place Bound Bottom")
		(35 "F.Fab" user "Ref Des/Assembly Top")
		(33 "B.Fab" user "Ref Des/Assembly Bottom")
	)
	(footprint ""
		(layer "B.Cu")
		(at 22.960584 -176.253902 -90)
		(property "Reference" "C1297"
			(at 0 0 90)
			(layer "B.SilkS")
			(hide yes)
			(effects
				(font
					(size 1.27 1.27)
				)
				(justify mirror)
			)
		)
		(property "Value" ""
			(at 0 0 90)
			(layer "B.Fab")
			(effects
				(font
					(size 1.27 1.27)
				)
				(justify mirror)
			)
		)
		(duplicate_pad_numbers_are_jumpers no)
		(fp_line
			(start -0.7874 0.4064)
			(end 0.7874 0.4064)
			(stroke
				(width 0.1524)
				(type default)
			)
			(layer "B.SilkS")
		)
		(fp_line
			(start 0.7874 0.4064)
			(end 0.7874 -0.4064)
			(stroke
				(width 0.1524)
				(type default)
			)
			(layer "B.SilkS")
		)
		(fp_line
			(start -0.7874 -0.4064)
			(end -0.7874 0.4064)
			(stroke
				(width 0.1524)
				(type default)
			)
			(layer "B.SilkS")
		)
		(fp_line
			(start 0.7874 -0.4064)
			(end -0.7874 -0.4064)
			(stroke
				(width 0.1524)
				(type default)
			)
			(layer "B.SilkS")
		)
		(fp_line
			(start -0.67945 0.3048)
			(end -0.120396 0.3048)
			(stroke
				(width 0.1)
				(type default)
			)
			(layer "B.Fab")
		)
		(fp_line
			(start -0.120396 0.3048)
			(end -0.120396 0.2794)
			(stroke
				(width 0.1)
				(type default)
			)
			(layer "B.Fab")
		)
		(fp_line
			(start 0.12065 0.3048)
			(end 0.67945 0.3048)
			(stroke
				(width 0.1)
				(type default)
			)
			(layer "B.Fab")
		)
		(fp_line
			(start 0.67945 0.3048)
			(end 0.67945 -0.305054)
			(stroke
				(width 0.1)
				(type default)
			)
			(layer "B.Fab")
		)
		(fp_line
			(start -0.120396 0.2794)
			(end 0.12065 0.2794)
			(stroke
				(width 0.1)
				(type default)
			)
			(layer "B.Fab")
		)
		(fp_line
			(start 0.12065 0.2794)
			(end 0.12065 0.3048)
			(stroke
				(width 0.1)
				(type default)
			)
			(layer "B.Fab")
		)
		(fp_line
			(start -0.12065 -0.2794)
			(end -0.12065 -0.3048)
			(stroke
				(width 0.1)
				(type default)
			)
			(layer "B.Fab")
		)
		(fp_line
			(start 0.12065 -0.2794)
			(end -0.12065 -0.2794)
			(stroke
				(width 0.1)
				(type default)
			)
			(layer "B.Fab")
		)
		(fp_line
			(start -0.67945 -0.3048)
			(end -0.67945 0.3048)
			(stroke
				(width 0.1)
				(type default)
			)
			(layer "B.Fab")
		)
		(fp_line
			(start -0.12065 -0.3048)
			(end -0.67945 -0.3048)
			(stroke
				(width 0.1)
				(type default)
			)
			(layer "B.Fab")
		)
		(fp_line
			(start 0.12065 -0.305054)
			(end 0.12065 -0.2794)
			(stroke
				(width 0.1)
				(type default)
			)
			(layer "B.Fab")
		)
		(fp_line
			(start 0.67945 -0.305054)
			(end 0.12065 -0.305054)
			(stroke
				(width 0.1)
				(type default)
			)
			(layer "B.Fab")
		)
		(pad "1" smd circle
			(at 0.40005 0 90)
			(size 0 0)
			(layers "B.Cu" "B.Mask" "B.Paste")
			(net "PWRGD_PVNN_MAIN_CPU1")
		)
		(pad "2" smd circle
			(at -0.40005 0 90)
			(size 0 0)
			(layers "B.Cu" "B.Mask" "B.Paste")
			(net "GND")
		)
	)
	(footprint ""
		(layer "B.Cu")
		(at 307.148738 -194.71767 90)
		(property "Reference" "R16"
			(at 0 0 90)
			(layer "B.SilkS")
			(hide yes)
			(effects
				(font
					(size 1.27 1.27)
				)
				(justify mirror)
			)
		)
		(property "Value" ""
			(at 0 0 90)
			(layer "B.Fab")
			(effects
				(font
					(size 1.27 1.27)
				)
				(justify mirror)
			)
		)
		(duplicate_pad_numbers_are_jumpers no)
		(fp_line
			(start 0.7874 -0.4064)
			(end -0.7874 -0.4064)
			(stroke
				(width 0.1524)
				(type default)
			)
			(layer "B.SilkS")
		)
		(fp_line
			(start -0.7874 -0.4064)
			(end -0.7874 0.4064)
			(stroke
				(width 0.1524)
				(type default)
			)
			(layer "B.SilkS")
		)
		(fp_line
			(start 0.7874 0.4064)
			(end 0.7874 -0.4064)
			(stroke
				(width 0.1524)
				(type default)
			)
			(layer "B.SilkS")
		)
		(fp_line
			(start -0.7874 0.4064)
			(end 0.7874 0.4064)
			(stroke
				(width 0.1524)
				(type default)
			)
			(layer "B.SilkS")
		)
		(fp_line
			(start 0.67945 -0.305054)
			(end 0.12065 -0.305054)
			(stroke
				(width 0.1)
				(type default)
			)
			(layer "B.Fab")
		)
		(fp_line
			(start 0.12065 -0.305054)
			(end 0.12065 -0.2794)
			(stroke
				(width 0.1)
				(type default)
			)
			(layer "B.Fab")
		)
		(fp_line
			(start -0.12065 -0.3048)
			(end -0.67945 -0.3048)
			(stroke
				(width 0.1)
				(type default)
			)
			(layer "B.Fab")
		)
		(fp_line
			(start -0.67945 -0.3048)
			(end -0.67945 0.3048)
			(stroke
				(width 0.1)
				(type default)
			)
			(layer "B.Fab")
		)
		(fp_line
			(start 0.12065 -0.2794)
			(end -0.12065 -0.2794)
			(stroke
				(width 0.1)
				(type default)
			)
			(layer "B.Fab")
		)
		(fp_line
			(start -0.12065 -0.2794)
			(end -0.12065 -0.3048)
			(stroke
				(width 0.1)
				(type default)
			)
			(layer "B.Fab")
		)
		(fp_line
			(start 0.12065 0.2794)
			(end 0.12065 0.3048)
			(stroke
				(width 0.1)
				(type default)
			)
			(layer "B.Fab")
		)
		(fp_line
			(start -0.120396 0.2794)
			(end 0.12065 0.2794)
			(stroke
				(width 0.1)
				(type default)
			)
			(layer "B.Fab")
		)
		(fp_line
			(start 0.67945 0.3048)
			(end 0.67945 -0.305054)
			(stroke
				(width 0.1)
				(type default)
			)
			(layer "B.Fab")
		)
		(fp_line
			(start 0.12065 0.3048)
			(end 0.67945 0.3048)
			(stroke
				(width 0.1)
				(type default)
			)
			(layer "B.Fab")
		)
		(fp_line
			(start -0.120396 0.3048)
			(end -0.120396 0.2794)
			(stroke
				(width 0.1)
				(type default)
			)
			(layer "B.Fab")
		)
		(fp_line
			(start -0.67945 0.3048)
			(end -0.120396 0.3048)
			(stroke
				(width 0.1)
				(type default)
			)
			(layer "B.Fab")
		)
		(pad "1" smd circle
			(at 0.40005 0 270)
			(size 0 0)
			(layers "B.Cu" "B.Mask" "B.Paste")
			(net "SVID_CLK1_CPU0")
		)
		(pad "2" smd circle
			(at -0.40005 0 270)
			(size 0 0)
			(layers "B.Cu" "B.Mask" "B.Paste")
			(net "SVID_CLK1_CPU0_R")
		)
	)
	(footprint ""
		(layer "B.Cu")
		(at 412.548324 -256.636266 -90)
		(property "Reference" "C510"
			(at 0 0 90)
			(layer "B.SilkS")
			(hide yes)
			(effects
				(font
					(size 1.27 1.27)
				)
				(justify mirror)
			)
		)
		(property "Value" ""
			(at 0 0 90)
			(layer "B.Fab")
			(effects
				(font
					(size 1.27 1.27)
				)
				(justify mirror)
			)
		)
		(duplicate_pad_numbers_are_jumpers no)
		(fp_line
			(start -1.524 0.762)
			(end 1.524 0.762)
			(stroke
				(width 0.1524)
				(type default)
			)
			(layer "B.SilkS")
		)
		(fp_line
			(start 1.524 0.762)
			(end 1.524 -0.762)
			(stroke
				(width 0.1524)
				(type default)
			)
			(layer "B.SilkS")
		)
		(fp_line
			(start -1.524 -0.762)
			(end -1.524 0.762)
			(stroke
				(width 0.1524)
				(type default)
			)
			(layer "B.SilkS")
		)
		(fp_line
			(start 1.524 -0.762)
			(end -1.524 -0.762)
			(stroke
				(width 0.1524)
				(type default)
			)
			(layer "B.SilkS")
		)
		(fp_line
			(start -1.1049 0.724916)
			(end -1.1049 -0.724916)
			(stroke
				(width 0.1)
				(type default)
			)
			(layer "B.Fab")
		)
		(fp_line
			(start 1.1049 0.724916)
			(end -1.1049 0.724916)
			(stroke
				(width 0.1)
				(type default)
			)
			(layer "B.Fab")
		)
		(fp_line
			(start -1.1049 -0.724916)
			(end 1.1049 -0.724916)
			(stroke
				(width 0.1)
				(type default)
			)
			(layer "B.Fab")
		)
		(fp_line
			(start 1.1049 -0.724916)
			(end 1.1049 0.724916)
			(stroke
				(width 0.1)
				(type default)
			)
			(layer "B.Fab")
		)
		(pad "1" smd rect
			(at 0.889 0 270)
			(size 1.016 1.27)
			(layers "B.Cu" "B.Mask" "B.Paste")
			(net "PVCCFA_EHV_FIVRA_CPU0")
		)
		(pad "2" smd rect
			(at -0.889 0 270)
			(size 1.016 1.27)
			(layers "B.Cu" "B.Mask" "B.Paste")
			(net "GND")
		)
	)
	(footprint ""
		(layer "B.Cu")
		(at 297.44416 -50.226468)
		(property "Reference" "C1187"
			(at 0 0 0)
			(layer "B.SilkS")
			(hide yes)
			(effects
				(font
					(size 1.27 1.27)
				)
				(justify mirror)
			)
		)
		(property "Value" ""
			(at 0 0 0)
			(layer "B.Fab")
			(effects
				(font
					(size 1.27 1.27)
				)
				(justify mirror)
			)
		)
		(duplicate_pad_numbers_are_jumpers no)
		(fp_line
			(start -1.2954 -0.5842)
			(end -1.2954 0.5842)
			(stroke
				(width 0.1524)
				(type default)
			)
			(layer "B.SilkS")
		)
		(fp_line
			(start -1.2954 0.5842)
			(end 1.2954 0.5842)
			(stroke
				(width 0.1524)
				(type default)
			)
			(layer "B.SilkS")
		)
		(fp_line
			(start 0 -0.5842)
			(end 0 0.5842)
			(stroke
				(width 0.1524)
				(type default)
			)
			(layer "B.SilkS")
		)
		(fp_line
			(start 1.2954 -0.5842)
			(end -1.2954 -0.5842)
			(stroke
				(width 0.1524)
				(type default)
			)
			(layer "B.SilkS")
		)
		(fp_line
			(start 1.2954 0.5842)
			(end 1.2954 -0.5842)
			(stroke
				(width 0.1524)
				(type default)
			)
			(layer "B.SilkS")
		)
		(fp_line
			(start -1.1938 -0.4064)
			(end -1.1938 0.4064)
			(stroke
				(width 0.1)
				(type default)
			)
			(layer "B.Fab")
		)
		(fp_line
			(start -1.1938 0.4064)
			(end -0.8636 0.4064)
			(stroke
				(width 0.1)
				(type default)
			)
			(layer "B.Fab")
		)
		(fp_line
			(start -0.8636 -0.4572)
			(end -0.8636 -0.4064)
			(stroke
				(width 0.1)
				(type default)
			)
			(layer "B.Fab")
		)
		(fp_line
			(start -0.8636 -0.4064)
			(end -1.1938 -0.4064)
			(stroke
				(width 0.1)
				(type default)
			)
			(layer "B.Fab")
		)
		(fp_line
			(start -0.8636 0.4064)
			(end -0.8636 0.4572)
			(stroke
				(width 0.1)
				(type default)
			)
			(layer "B.Fab")
		)
		(fp_line
			(start -0.8636 0.4572)
			(end 0.8636 0.4572)
			(stroke
				(width 0.1)
				(type default)
			)
			(layer "B.Fab")
		)
		(fp_line
			(start 0.8636 -0.4572)
			(end -0.8636 -0.4572)
			(stroke
				(width 0.1)
				(type default)
			)
			(layer "B.Fab")
		)
		(fp_line
			(start 0.8636 -0.4064)
			(end 0.8636 -0.4572)
			(stroke
				(width 0.1)
				(type default)
			)
			(layer "B.Fab")
		)
		(fp_line
			(start 0.8636 0.4064)
			(end 1.1938 0.4064)
			(stroke
				(width 0.1)
				(type default)
			)
			(layer "B.Fab")
		)
		(fp_line
			(start 0.8636 0.4572)
			(end 0.8636 0.4064)
			(stroke
				(width 0.1)
				(type default)
			)
			(layer "B.Fab")
		)
		(fp_line
			(start 1.1938 -0.4064)
			(end 0.8636 -0.4064)
			(stroke
				(width 0.1)
				(type default)
			)
			(layer "B.Fab")
		)
		(fp_line
			(start 1.1938 0.4064)
			(end 1.1938 -0.4064)
			(stroke
				(width 0.1)
				(type default)
			)
			(layer "B.Fab")
		)
		(pad "1" smd rect
			(at 0.7366 0 270)
			(size 0.7112 0.8128)
			(layers "B.Cu" "B.Mask" "B.Paste")
			(net "P1V05_PCH_AUX")
		)
		(pad "2" smd rect
			(at -0.7366 0 270)
			(size 0.7112 0.8128)
			(layers "B.Cu" "B.Mask" "B.Paste")
			(net "GND")
		)
	)
	(footprint ""
		(layer "B.Cu")
		(at 319.58153 -32.470598 -90)
		(property "Reference" "R1744"
			(at 0 0 90)
			(layer "B.SilkS")
			(hide yes)
			(effects
				(font
					(size 1.27 1.27)
				)
				(justify mirror)
			)
		)
		(property "Value" ""
			(at 0 0 90)
			(layer "B.Fab")
			(effects
				(font
					(size 1.27 1.27)
				)
				(justify mirror)
			)
		)
		(duplicate_pad_numbers_are_jumpers no)
		(fp_line
			(start -0.7874 0.4064)
			(end 0.7874 0.4064)
			(stroke
				(width 0.1524)
				(type default)
			)
			(layer "B.SilkS")
		)
		(fp_line
			(start 0.7874 0.4064)
			(end 0.7874 -0.4064)
			(stroke
				(width 0.1524)
				(type default)
			)
			(layer "B.SilkS")
		)
		(fp_line
			(start -0.7874 -0.4064)
			(end -0.7874 0.4064)
			(stroke
				(width 0.1524)
				(type default)
			)
			(layer "B.SilkS")
		)
		(fp_line
			(start 0.7874 -0.4064)
			(end -0.7874 -0.4064)
			(stroke
				(width 0.1524)
				(type default)
			)
			(layer "B.SilkS")
		)
		(fp_line
			(start -0.67945 0.3048)
			(end -0.120396 0.3048)
			(stroke
				(width 0.1)
				(type default)
			)
			(layer "B.Fab")
		)
		(fp_line
			(start -0.120396 0.3048)
			(end -0.120396 0.2794)
			(stroke
				(width 0.1)
				(type default)
			)
			(layer "B.Fab")
		)
		(fp_line
			(start 0.12065 0.3048)
			(end 0.67945 0.3048)
			(stroke
				(width 0.1)
				(type default)
			)
			(layer "B.Fab")
		)
		(fp_line
			(start 0.67945 0.3048)
			(end 0.67945 -0.305054)
			(stroke
				(width 0.1)
				(type default)
			)
			(layer "B.Fab")
		)
		(fp_line
			(start -0.120396 0.2794)
			(end 0.12065 0.2794)
			(stroke
				(width 0.1)
				(type default)
			)
			(layer "B.Fab")
		)
		(fp_line
			(start 0.12065 0.2794)
			(end 0.12065 0.3048)
			(stroke
				(width 0.1)
				(type default)
			)
			(layer "B.Fab")
		)
		(fp_line
			(start -0.12065 -0.2794)
			(end -0.12065 -0.3048)
			(stroke
				(width 0.1)
				(type default)
			)
			(layer "B.Fab")
		)
		(fp_line
			(start 0.12065 -0.2794)
			(end -0.12065 -0.2794)
			(stroke
				(width 0.1)
				(type default)
			)
			(layer "B.Fab")
		)
		(fp_line
			(start -0.67945 -0.3048)
			(end -0.67945 0.3048)
			(stroke
				(width 0.1)
				(type default)
			)
			(layer "B.Fab")
		)
		(fp_line
			(start -0.12065 -0.3048)
			(end -0.67945 -0.3048)
			(stroke
				(width 0.1)
				(type default)
			)
			(layer "B.Fab")
		)
		(fp_line
			(start 0.12065 -0.305054)
			(end 0.12065 -0.2794)
			(stroke
				(width 0.1)
				(type default)
			)
			(layer "B.Fab")
		)
		(fp_line
			(start 0.67945 -0.305054)
			(end 0.12065 -0.305054)
			(stroke
				(width 0.1)
				(type default)
			)
			(layer "B.Fab")
		)
		(pad "1" smd circle
			(at 0.40005 0 90)
			(size 0 0)
			(layers "B.Cu" "B.Mask" "B.Paste")
			(net "FM_BMC_PWRBTN_OUT_N")
		)
		(pad "2" smd circle
			(at -0.40005 0 90)
			(size 0 0)
			(layers "B.Cu" "B.Mask" "B.Paste")
			(net "FM_BMC_PWRBTN_N")
		)
	)
	(footprint ""
		(layer "B.Cu")
		(at 381.213868 -189.29096)
		(property "Reference" "R1242"
			(at 0 0 0)
			(layer "B.SilkS")
			(hide yes)
			(effects
				(font
					(size 1.27 1.27)
				)
				(justify mirror)
			)
		)
		(property "Value" ""
			(at 0 0 0)
			(layer "B.Fab")
			(effects
				(font
					(size 1.27 1.27)
				)
				(justify mirror)
			)
		)
		(duplicate_pad_numbers_are_jumpers no)
		(fp_line
			(start -0.7874 -0.4064)
			(end -0.7874 0.4064)
			(stroke
				(width 0.1524)
				(type default)
			)
			(layer "B.SilkS")
		)
		(fp_line
			(start -0.7874 0.4064)
			(end 0.7874 0.4064)
			(stroke
				(width 0.1524)
				(type default)
			)
			(layer "B.SilkS")
		)
		(fp_line
			(start 0.7874 -0.4064)
			(end -0.7874 -0.4064)
			(stroke
				(width 0.1524)
				(type default)
			)
			(layer "B.SilkS")
		)
		(fp_line
			(start 0.7874 0.4064)
			(end 0.7874 -0.4064)
			(stroke
				(width 0.1524)
				(type default)
			)
			(layer "B.SilkS")
		)
		(fp_line
			(start -0.67945 -0.3048)
			(end -0.67945 0.3048)
			(stroke
				(width 0.1)
				(type default)
			)
			(layer "B.Fab")
		)
		(fp_line
			(start -0.67945 0.3048)
			(end -0.120396 0.3048)
			(stroke
				(width 0.1)
				(type default)
			)
			(layer "B.Fab")
		)
		(fp_line
			(start -0.12065 -0.3048)
			(end -0.67945 -0.3048)
			(stroke
				(width 0.1)
				(type default)
			)
			(layer "B.Fab")
		)
		(fp_line
			(start -0.12065 -0.2794)
			(end -0.12065 -0.3048)
			(stroke
				(width 0.1)
				(type default)
			)
			(layer "B.Fab")
		)
		(fp_line
			(start -0.120396 0.2794)
			(end 0.12065 0.2794)
			(stroke
				(width 0.1)
				(type default)
			)
			(layer "B.Fab")
		)
		(fp_line
			(start -0.120396 0.3048)
			(end -0.120396 0.2794)
			(stroke
				(width 0.1)
				(type default)
			)
			(layer "B.Fab")
		)
		(fp_line
			(start 0.12065 -0.305054)
			(end 0.12065 -0.2794)
			(stroke
				(width 0.1)
				(type default)
			)
			(layer "B.Fab")
		)
		(fp_line
			(start 0.12065 -0.2794)
			(end -0.12065 -0.2794)
			(stroke
				(width 0.1)
				(type default)
			)
			(layer "B.Fab")
		)
		(fp_line
			(start 0.12065 0.2794)
			(end 0.12065 0.3048)
			(stroke
				(width 0.1)
				(type default)
			)
			(layer "B.Fab")
		)
		(fp_line
			(start 0.12065 0.3048)
			(end 0.67945 0.3048)
			(stroke
				(width 0.1)
				(type default)
			)
			(layer "B.Fab")
		)
		(fp_line
			(start 0.67945 -0.305054)
			(end 0.12065 -0.305054)
			(stroke
				(width 0.1)
				(type default)
			)
			(layer "B.Fab")
		)
		(fp_line
			(start 0.67945 0.3048)
			(end 0.67945 -0.305054)
			(stroke
				(width 0.1)
				(type default)
			)
			(layer "B.Fab")
		)
		(pad "1" smd circle
			(at 0.40005 0 180)
			(size 0 0)
			(layers "B.Cu" "B.Mask" "B.Paste")
			(net "PVNN_TERM_CPU0")
		)
		(pad "2" smd circle
			(at -0.40005 0 180)
			(size 0 0)
			(layers "B.Cu" "B.Mask" "B.Paste")
			(net "H_CPU_PM_FAST_WAKE_N")
		)
	)
)
